FILE_TYPE = CONNECTIVITY;
{Allegro Design Entry HDL 16.6-p007 (v16-6-112F) 10/10/2012}
"PAGE_NUMBER" = 178;
0"NC";
1"P3V3_STBY\g";
2"P3V3_STBY\g";
3"SGPIO_PCH_SSATA_DOUT0";
4"SGPIO_PCH_SSATA_LOAD";
5"SGPIO_PCH_SSATA_CLOCK";
6"SGPIO_PCH_SATA_LOAD";
7"SGPIO_PCH_SATA_DOUT0";
8"SGPIO_PCH_SATA_CLOCK";
9"SGPIO_PCH_SSATA_LOAD_R";
10"SGPIO_PCH_SATA_LOAD_R";
11"SGPIO_PCH_SSATA_DOUT0_R";
12"SGPIO_PCH_SSATA_CLOCK_R";
13"SGPIO_PCH_SATA_CLOCK_R";
14"SGPIO_PCH_SATA_DOUT0_R";
%"RES"
"1","(-800,3725)","0","mstr_discrete","I1";
;
CDS_SEC"1"
ROOM"ST_SATA"
CDS_LOCATION"R8D20"
SEC"1"
BOM_COST"ST_SATA"
SEC_TYPE"0402"
CDS_LIB"mstr_discrete"
WATTAGE"1/16W"
MATERIAL"CHIP"
PACK_TYPE"0402"
TOLERANCE"1%"
VALUE"49.9"
PART_NUMBER"G21796-047"
LOCATION"R8D20";
"B"
$PN"2"10;
"A"
$PN"1"6;
%"RES"
"1","(-800,3425)","0","mstr_discrete","I11";
;
CDS_SEC"1"
CDS_LOCATION"R2N31"
ROOM"ST_SATA"
SEC"1"
BOM_COST"ST_SATA"
SEC_TYPE"0402"
CDS_LIB"mstr_discrete"
WATTAGE"1/16W"
MATERIAL"CHIP"
PACK_TYPE"0402"
TOLERANCE"1%"
VALUE"49.9"
PART_NUMBER"G21796-047"
LOCATION"R2N31";
"B"
$PN"2"13;
"A"
$PN"1"8;
%"RES"
"2","(225,4125)","2","mstr_discrete","I12";
;
CDS_SEC"1"
ROOM"ST_SATA"
CDS_LOCATION"R2L15"
SEC"1"
BOM_COST"ST_SATA"
SEC_TYPE"0402"
CDS_LIB"mstr_discrete"
WATTAGE"1/16W"
MATERIAL"CHIP"
PACK_TYPE"0402"
TOLERANCE"1%"
VALUE"2.0K"
PART_NUMBER"G21796-001"
LOCATION"R2L15";
"A"
$PN"1"2;
"B"
$PN"2"14;
%"RES"
"2","(575,4125)","2","mstr_discrete","I13";
;
CDS_SEC"1"
ROOM"ST_SATA"
CDS_LOCATION"R2L11"
SEC"1"
BOM_COST"ST_SATA"
SEC_TYPE"0402"
CDS_LIB"mstr_discrete"
WATTAGE"1/16W"
MATERIAL"CHIP"
PACK_TYPE"0402"
TOLERANCE"1%"
VALUE"2.0K"
PART_NUMBER"G21796-001"
LOCATION"R2L11";
"A"
$PN"1"2;
"B"
$PN"2"13;
%"RES"
"2","(475,2225)","2","mstr_discrete","I17";
;
CDS_SEC"1"
ROOM"ST_SATA"
CDS_LOCATION"R2L6"
SEC"1"
CDS_LIB"mstr_discrete"
SEC_TYPE"0402"
BOM_COST"ST_SATA"
WATTAGE"1/16W"
MATERIAL"CHIP"
PACK_TYPE"0402"
TOLERANCE"1%"
VALUE"2.0K"
PART_NUMBER"G21796-001"
LOCATION"R2L6";
"A"
$PN"1"1;
"B"
$PN"2"12;
%"RES"
"2","(125,2225)","2","mstr_discrete","I18";
;
CDS_SEC"1"
ROOM"ST_SATA"
CDS_LOCATION"R2L4"
SEC"1"
CDS_LIB"mstr_discrete"
SEC_TYPE"0402"
BOM_COST"ST_SATA"
WATTAGE"1/16W"
MATERIAL"CHIP"
PACK_TYPE"0402"
TOLERANCE"1%"
VALUE"2.0K"
PART_NUMBER"G21796-001"
LOCATION"R2L4";
"A"
$PN"1"1;
"B"
$PN"2"11;
%"P3V3_STBY"
"1","(-200,2625)","0","mstr_symbols","I19";
;
HDL_POWER"P3V3_STBY"
BODY_TYPE"PLUMBING"
SIZE"1B"
CDS_LIB"mstr_symbols"
VOLTAGE"3.3V";
"G\NAC"1;
%"RES"
"2","(-200,4125)","2","mstr_discrete","I2";
;
CDS_SEC"1"
ROOM"ST_SATA"
CDS_LOCATION"R2L12"
SEC"1"
CDS_LIB"mstr_discrete"
SEC_TYPE"0402"
BOM_COST"ST_SATA"
WATTAGE"1/16W"
MATERIAL"CHIP"
PACK_TYPE"0402"
TOLERANCE"1%"
VALUE"2.0K"
PART_NUMBER"G21796-001"
LOCATION"R2L12";
"A"
$PN"1"2;
"B"
$PN"2"10;
%"RES"
"2","(-200,2225)","2","mstr_discrete","I20";
;
CDS_SEC"1"
ROOM"ST_SATA"
CDS_LOCATION"R2L5"
SEC"1"
BOM_COST"ST_SATA"
SEC_TYPE"0402"
CDS_LIB"mstr_discrete"
WATTAGE"1/16W"
MATERIAL"CHIP"
PACK_TYPE"0402"
TOLERANCE"1%"
VALUE"2.0K"
PART_NUMBER"G21796-001"
LOCATION"R2L5";
"A"
$PN"1"1;
"B"
$PN"2"9;
%"RES"
"1","(-800,1675)","0","mstr_discrete","I21";
;
CDS_SEC"1"
ROOM"ST_SATA"
CDS_LOCATION"R8B29"
SEC"1"
CDS_LIB"mstr_discrete"
SEC_TYPE"0402"
BOM_COST"ST_SATA"
WATTAGE"1/16W"
MATERIAL"CHIP"
PACK_TYPE"0402"
TOLERANCE"1%"
VALUE"49.9"
PART_NUMBER"G21796-047"
LOCATION"R8B29";
"B"
$PN"2"11;
"A"
$PN"1"3;
%"RES"
"1","(-800,1825)","0","mstr_discrete","I22";
;
CDS_SEC"1"
ROOM"ST_SATA"
CDS_LOCATION"R2N19"
SEC"1"
CDS_LIB"mstr_discrete"
SEC_TYPE"0402"
BOM_COST"ST_SATA"
WATTAGE"1/16W"
MATERIAL"CHIP"
PACK_TYPE"0402"
TOLERANCE"1%"
VALUE"49.9"
PART_NUMBER"G21796-047"
LOCATION"R2N19";
"B"
$PN"2"9;
"A"
$PN"1"4;
%"RES"
"1","(-800,1525)","0","mstr_discrete","I23";
;
CDS_SEC"1"
ROOM"ST_SATA"
CDS_LOCATION"R2N22"
SEC"1"
CDS_LIB"mstr_discrete"
SEC_TYPE"0402"
BOM_COST"ST_SATA"
WATTAGE"1/16W"
MATERIAL"CHIP"
PACK_TYPE"0402"
TOLERANCE"1%"
VALUE"49.9"
PART_NUMBER"G21796-047"
LOCATION"R2N22";
"B"
$PN"2"12;
"A"
$PN"1"5;
%"P3V3_STBY"
"1","(-200,4525)","0","mstr_symbols","I5";
;
HDL_POWER"P3V3_STBY"
BODY_TYPE"PLUMBING"
CDS_LIB"mstr_symbols"
SIZE"1B"
VOLTAGE"3.3V";
"G\NAC"2;
%"RES"
"1","(-800,3575)","0","mstr_discrete","I8";
;
CDS_SEC"1"
ROOM"ST_SATA"
CDS_LOCATION"R8D19"
SEC"1"
BOM_COST"ST_SATA"
SEC_TYPE"0402"
CDS_LIB"mstr_discrete"
WATTAGE"1/16W"
MATERIAL"CHIP"
PACK_TYPE"0402"
TOLERANCE"1%"
VALUE"49.9"
PART_NUMBER"G21796-047"
LOCATION"R8D19";
"B"
$PN"2"14;
"A"
$PN"1"7;
END.
